(kicad_pcb
	(version 20260206)
	(generator "pcbnew")
	(generator_version "10.0")
	(general
		(thickness 1.6)
		(legacy_teardrops no)
	)
	(paper "A4")
	(title_block
		(title "Bryce Canyon_F.DPB_16315-1-OCP.brd")
		(comment 1 "Bryce Canyon / footprints 1124-1131 of 2223")
	)
	(layers
		(0 "F.Cu" signal "TOP")
		(4 "In1.Cu" signal "L2GND")
		(6 "In2.Cu" signal "L3")
		(8 "In3.Cu" signal "L4GND")
		(10 "In4.Cu" signal "L5")
		(12 "In5.Cu" signal "L6VCC")
		(14 "In6.Cu" signal "L7VCC")
		(16 "In7.Cu" signal "L8")
		(18 "In8.Cu" signal "L9GND")
		(20 "In9.Cu" signal "L10")
		(22 "In10.Cu" signal "L11GND")
		(2 "B.Cu" signal "BOTTOM")
		(9 "F.Adhes" user "F.Adhesive")
		(11 "B.Adhes" user "B.Adhesive")
		(13 "F.Paste" user "Package Geometry/Pastemask Top")
		(15 "B.Paste" user "Package Geometry/Pastemask Bottom")
		(5 "F.SilkS" user "Ref Des/Silkscreen Top")
		(7 "B.SilkS" user "Ref Des/Silkscreen Bottom")
		(1 "F.Mask" user "Board Geometry/Soldermask Top")
		(3 "B.Mask" user "Board Geometry/Soldermask Bottom")
		(17 "Dwgs.User" user "User.Drawings")
		(19 "Cmts.User" user "User.Comments")
		(21 "Eco1.User" user "User.Eco1")
		(23 "Eco2.User" user "User.Eco2")
		(25 "Edge.Cuts" user "Board Geometry/Outline")
		(27 "Margin" user)
		(31 "F.CrtYd" user "Package Geometry/Place Bound Top")
		(29 "B.CrtYd" user "Package Geometry/Place Bound Bottom")
		(35 "F.Fab" user "Ref Des/Assembly Top")
		(33 "B.Fab" user "Ref Des/Assembly Bottom")
	)
	(footprint ""
		(layer "F.Cu")
		(at 299.351446 -25.74544 90)
		(property "Reference" "R1128"
			(at 0 0 90)
			(layer "F.SilkS")
			(hide yes)
			(effects
				(font
					(size 1.27 1.27)
				)
			)
		)
		(property "Value" "100KR2F-L1-GP"
			(at 0.064008 -3.993896 90)
			(unlocked yes)
			(layer "F.Fab")
			(hide yes)
			(effects
				(font
					(size 1.016 1.016)
					(thickness 0.1524)
				)
			)
		)
		(property "Device Type" "R402H16"
			(at 0.064008 -5.517896 90)
			(unlocked yes)
			(layer "F.Fab")
			(hide yes)
			(effects
				(font
					(size 1.016 1.016)
					(thickness 0.1524)
				)
			)
		)
		(duplicate_pad_numbers_are_jumpers no)
		(fp_line
			(start 0.508 -0.9398)
			(end -0.508 -0.9398)
			(stroke
				(width 0.1524)
				(type default)
			)
			(layer "F.SilkS")
		)
		(fp_line
			(start -0.508 -0.9398)
			(end -0.508 0.9398)
			(stroke
				(width 0.1524)
				(type default)
			)
			(layer "F.SilkS")
		)
		(fp_rect
			(start -0.508 0.9398)
			(end 0.508 -0.9398)
			(stroke
				(width 0)
				(type default)
			)
			(fill no)
			(layer "F.CrtYd")
		)
		(fp_rect
			(start -0.508 0.9398)
			(end 0.508 -0.9398)
			(stroke
				(width 0)
				(type default)
			)
			(fill no)
			(layer "F.Fab")
		)
		(pad "1" smd custom
			(at 0 -0.4445 90)
			(size 0.1397 0.1397)
			(layers "F.Cu" "F.Mask" "F.Paste")
			(net "PCIE_COMP_B_TO_IOM_B_RST_3")
			(options
				(clearance outline)
				(anchor circle)
			)
			(primitives
				(gr_poly
					(pts
						(arc
							(start -0.1778 -0.2794)
							(mid -0.249642 -0.249642)
							(end -0.2794 -0.1778)
						)
						(arc
							(start -0.2794 0.1778)
							(mid -0.249642 0.249642)
							(end -0.1778 0.2794)
						)
						(arc
							(start 0.1778 0.2794)
							(mid 0.249642 0.249642)
							(end 0.2794 0.1778)
						)
						(arc
							(start 0.2794 -0.1778)
							(mid 0.249642 -0.249642)
							(end 0.1778 -0.2794)
						)
					)
					(width 0)
					(fill yes)
				)
			)
		)
		(pad "2" smd custom
			(at 0 0.4445 90)
			(size 0.1397 0.1397)
			(layers "F.Cu" "F.Mask" "F.Paste")
			(net "GND")
			(options
				(clearance outline)
				(anchor circle)
			)
			(primitives
				(gr_poly
					(pts
						(arc
							(start -0.1778 -0.2794)
							(mid -0.249642 -0.249642)
							(end -0.2794 -0.1778)
						)
						(arc
							(start -0.2794 0.1778)
							(mid -0.249642 0.249642)
							(end -0.1778 0.2794)
						)
						(arc
							(start 0.1778 0.2794)
							(mid 0.249642 0.249642)
							(end 0.2794 0.1778)
						)
						(arc
							(start 0.2794 -0.1778)
							(mid 0.249642 -0.249642)
							(end 0.1778 -0.2794)
						)
					)
					(width 0)
					(fill yes)
				)
			)
		)
	)
	(footprint ""
		(layer "F.Cu")
		(at 474.006926 -64.683894 90)
		(property "Reference" "R936"
			(at 0 0 90)
			(layer "F.SilkS")
			(hide yes)
			(effects
				(font
					(size 1.27 1.27)
				)
			)
		)
		(property "Value" "2R6F-GP"
			(at -0.0508 -4.8514 90)
			(unlocked yes)
			(layer "F.Fab")
			(hide yes)
			(effects
				(font
					(size 1.016 1.016)
					(thickness 0.1524)
				)
			)
		)
		(property "Device Type" "R1206H26"
			(at 0 -6.3754 90)
			(unlocked yes)
			(layer "F.Fab")
			(hide yes)
			(effects
				(font
					(size 1.016 1.016)
					(thickness 0.1524)
				)
			)
		)
		(duplicate_pad_numbers_are_jumpers no)
		(fp_line
			(start 1.016 -2.2352)
			(end 1.016 2.2352)
			(stroke
				(width 0.1524)
				(type default)
			)
			(layer "F.SilkS")
		)
		(fp_line
			(start -1.016 -2.2352)
			(end 1.016 -2.2352)
			(stroke
				(width 0.1524)
				(type default)
			)
			(layer "F.SilkS")
		)
		(fp_line
			(start 1.016 2.2352)
			(end -1.016 2.2352)
			(stroke
				(width 0.1524)
				(type default)
			)
			(layer "F.SilkS")
		)
		(fp_line
			(start -1.016 2.2352)
			(end -1.016 -2.2352)
			(stroke
				(width 0.1524)
				(type default)
			)
			(layer "F.SilkS")
		)
		(fp_rect
			(start -1.0922 2.3114)
			(end 1.0922 -2.3114)
			(stroke
				(width 0)
				(type default)
			)
			(fill no)
			(layer "F.CrtYd")
		)
		(fp_poly
			(pts
				(xy -1.0922 -2.3114) (xy 1.0922 -2.3114) (xy 1.0922 2.3114) (xy -1.0922 2.3114)
			)
			(stroke
				(width 0)
				(type default)
			)
			(fill no)
			(layer "F.Fab")
		)
		(pad "1" smd rect
			(at 0 -1.397 90)
			(size 1.651 1.27)
			(layers "F.Cu" "F.Mask" "F.Paste")
			(net "P12V_HDD35")
		)
		(pad "2" smd rect
			(at 0 1.397 90)
			(size 1.651 1.27)
			(layers "F.Cu" "F.Mask" "F.Paste")
			(net "12V_PRE_35")
		)
	)
	(footprint ""
		(layer "F.Cu")
		(at 368.862102 -47.792894 90)
		(property "Reference" "D31"
			(at 0 0 90)
			(layer "F.SilkS")
			(hide yes)
			(effects
				(font
					(size 1.27 1.27)
				)
			)
		)
		(property "Value" "RB551V30-GP"
			(at 0 -6.7818 90)
			(unlocked yes)
			(layer "F.Fab")
			(hide yes)
			(effects
				(font
					(size 1.016 1.016)
					(thickness 0.1524)
				)
			)
		)
		(property "Device Type" "SOD323AKH38"
			(at 0 -8.6868 90)
			(unlocked yes)
			(layer "F.Fab")
			(hide yes)
			(effects
				(font
					(size 1.016 1.016)
					(thickness 0.1524)
				)
			)
		)
		(duplicate_pad_numbers_are_jumpers no)
		(fp_line
			(start 0.889 -1.9304)
			(end 0.889 2.159)
			(stroke
				(width 0.1524)
				(type default)
			)
			(layer "F.SilkS")
		)
		(fp_line
			(start -0.889 -1.9304)
			(end 0.889 -1.9304)
			(stroke
				(width 0.1524)
				(type default)
			)
			(layer "F.SilkS")
		)
		(fp_line
			(start 0.762 2.0574)
			(end -0.762 2.0574)
			(stroke
				(width 0.508)
				(type default)
			)
			(layer "F.SilkS")
		)
		(fp_line
			(start 0.889 2.159)
			(end -0.889 2.159)
			(stroke
				(width 0.1524)
				(type default)
			)
			(layer "F.SilkS")
		)
		(fp_line
			(start -0.889 2.159)
			(end -0.889 -1.9304)
			(stroke
				(width 0.1524)
				(type default)
			)
			(layer "F.SilkS")
		)
		(fp_rect
			(start -1.016 2.3114)
			(end 1.016 -2.0066)
			(stroke
				(width 0)
				(type default)
			)
			(fill no)
			(layer "F.CrtYd")
		)
		(fp_poly
			(pts
				(xy -1.016 -2.0066) (xy 1.016 -2.0066) (xy 1.016 2.3114) (xy -1.016 2.3114)
			)
			(stroke
				(width 0)
				(type default)
			)
			(fill no)
			(layer "F.Fab")
		)
		(pad "A" smd rect
			(at 0 -1.143 90)
			(size 0.5588 1.016)
			(layers "F.Cu" "F.Mask" "F.Paste")
			(net "SW_HDD_R31")
		)
		(pad "K" smd rect
			(at 0 1.143 90)
			(size 0.5588 1.016)
			(layers "F.Cu" "F.Mask" "F.Paste")
			(net "SW_HDD_N31")
		)
	)
	(footprint ""
		(layer "F.Cu")
		(at 23.936198 -186.287918)
		(property "Reference" "C202"
			(at 0 0 0)
			(layer "F.SilkS")
			(hide yes)
			(effects
				(font
					(size 1.27 1.27)
				)
			)
		)
		(property "Value" "SC4D7U25V5KX-1-GP"
			(at -0.0762 -6.1214 0)
			(unlocked yes)
			(layer "F.Fab")
			(hide yes)
			(effects
				(font
					(size 1.016 1.016)
					(thickness 0.1524)
				)
			)
		)
		(property "Device Type" "C805H58"
			(at -0.0762 -8.1534 0)
			(unlocked yes)
			(layer "F.Fab")
			(hide yes)
			(effects
				(font
					(size 1.016 1.016)
					(thickness 0.1524)
				)
			)
		)
		(duplicate_pad_numbers_are_jumpers no)
		(fp_line
			(start 0.635 0)
			(end -0.635 0)
			(stroke
				(width 0.508)
				(type default)
			)
			(layer "F.SilkS")
		)
		(fp_rect
			(start -0.9652 1.778)
			(end 0.9652 -1.778)
			(stroke
				(width 0)
				(type default)
			)
			(fill no)
			(layer "F.CrtYd")
		)
		(fp_poly
			(pts
				(xy -0.9652 -1.778) (xy 0.9652 -1.778) (xy 0.9652 1.778) (xy -0.9652 1.778)
			)
			(stroke
				(width 0)
				(type default)
			)
			(fill no)
			(layer "F.Fab")
		)
		(pad "1" smd rect
			(at 0 -0.9652)
			(size 1.397 1.143)
			(layers "F.Cu" "F.Mask" "F.Paste")
			(net "P12V_HDD12")
		)
		(pad "2" smd rect
			(at 0 0.9652)
			(size 1.397 1.143)
			(layers "F.Cu" "F.Mask" "F.Paste")
			(net "GND")
		)
	)
	(footprint ""
		(layer "F.Cu")
		(at 158.663386 -273.660616 90)
		(property "Reference" "C91"
			(at 0 0 90)
			(layer "F.SilkS")
			(hide yes)
			(effects
				(font
					(size 1.27 1.27)
				)
			)
		)
		(property "Value" "SCD01U16V1KX-GP"
			(at -2.8321 -1.7399 90)
			(unlocked yes)
			(layer "F.Fab")
			(hide yes)
			(effects
				(font
					(size 1.016 1.016)
					(thickness 0.1524)
				)
			)
		)
		(property "Device Type" "C0201H13"
			(at -2.8321 -3.2639 90)
			(unlocked yes)
			(layer "F.Fab")
			(hide yes)
			(effects
				(font
					(size 1.016 1.016)
					(thickness 0.1524)
				)
			)
		)
		(duplicate_pad_numbers_are_jumpers no)
		(fp_rect
			(start -0.2794 0.6477)
			(end 0.2794 -0.6477)
			(stroke
				(width 0)
				(type default)
			)
			(fill no)
			(layer "F.CrtYd")
		)
		(fp_rect
			(start -0.2794 0.6477)
			(end 0.2794 -0.6477)
			(stroke
				(width 0)
				(type default)
			)
			(fill no)
			(layer "F.Fab")
		)
		(pad "1" smd custom
			(at 0 -0.2794 90)
			(size 0.0762 0.0762)
			(layers "F.Cu" "F.Mask" "F.Paste")
			(net "SAS_HDD_RX_P4")
			(options
				(clearance outline)
				(anchor circle)
			)
			(primitives
				(gr_poly
					(pts
						(arc
							(start 0.1524 -0.127)
							(mid 0.137521 -0.162921)
							(end 0.1016 -0.1778)
						)
						(arc
							(start -0.1016 -0.1778)
							(mid -0.137521 -0.162921)
							(end -0.1524 -0.127)
						)
						(arc
							(start -0.1524 0.127)
							(mid -0.137521 0.162921)
							(end -0.1016 0.1778)
						)
						(arc
							(start 0.1016 0.1778)
							(mid 0.137521 0.162921)
							(end 0.1524 0.127)
						)
					)
					(width 0)
					(fill yes)
				)
			)
		)
		(pad "2" smd custom
			(at 0 0.2794 90)
			(size 0.0762 0.0762)
			(layers "F.Cu" "F.Mask" "F.Paste")
			(net "PHY_SCC_A_TO_DRV_A_4_DP")
			(options
				(clearance outline)
				(anchor circle)
			)
			(primitives
				(gr_poly
					(pts
						(arc
							(start 0.1524 -0.127)
							(mid 0.137521 -0.162921)
							(end 0.1016 -0.1778)
						)
						(arc
							(start -0.1016 -0.1778)
							(mid -0.137521 -0.162921)
							(end -0.1524 -0.127)
						)
						(arc
							(start -0.1524 0.127)
							(mid -0.137521 0.162921)
							(end -0.1016 0.1778)
						)
						(arc
							(start 0.1016 0.1778)
							(mid 0.137521 0.162921)
							(end 0.1524 0.127)
						)
					)
					(width 0)
					(fill yes)
				)
			)
		)
	)
	(footprint ""
		(layer "F.Cu")
		(at 190.213488 -43.660568 90)
		(property "Reference" "C416"
			(at 0 0 90)
			(layer "F.SilkS")
			(hide yes)
			(effects
				(font
					(size 1.27 1.27)
				)
			)
		)
		(property "Value" "SCD01U16V1KX-GP"
			(at -2.8321 -1.7399 90)
			(unlocked yes)
			(layer "F.Fab")
			(hide yes)
			(effects
				(font
					(size 1.016 1.016)
					(thickness 0.1524)
				)
			)
		)
		(property "Device Type" "C0201H13"
			(at -2.8321 -3.2639 90)
			(unlocked yes)
			(layer "F.Fab")
			(hide yes)
			(effects
				(font
					(size 1.016 1.016)
					(thickness 0.1524)
				)
			)
		)
		(duplicate_pad_numbers_are_jumpers no)
		(fp_rect
			(start -0.2794 0.6477)
			(end 0.2794 -0.6477)
			(stroke
				(width 0)
				(type default)
			)
			(fill no)
			(layer "F.CrtYd")
		)
		(fp_rect
			(start -0.2794 0.6477)
			(end 0.2794 -0.6477)
			(stroke
				(width 0)
				(type default)
			)
			(fill no)
			(layer "F.Fab")
		)
		(pad "1" smd custom
			(at 0 -0.2794 90)
			(size 0.0762 0.0762)
			(layers "F.Cu" "F.Mask" "F.Paste")
			(net "SAS_HDD_RX_P29")
			(options
				(clearance outline)
				(anchor circle)
			)
			(primitives
				(gr_poly
					(pts
						(arc
							(start 0.1524 -0.127)
							(mid 0.137521 -0.162921)
							(end 0.1016 -0.1778)
						)
						(arc
							(start -0.1016 -0.1778)
							(mid -0.137521 -0.162921)
							(end -0.1524 -0.127)
						)
						(arc
							(start -0.1524 0.127)
							(mid -0.137521 0.162921)
							(end -0.1016 0.1778)
						)
						(arc
							(start 0.1016 0.1778)
							(mid 0.137521 0.162921)
							(end 0.1524 0.127)
						)
					)
					(width 0)
					(fill yes)
				)
			)
		)
		(pad "2" smd custom
			(at 0 0.2794 90)
			(size 0.0762 0.0762)
			(layers "F.Cu" "F.Mask" "F.Paste")
			(net "PHY_SCC_A_TO_DRV_A_29_DP")
			(options
				(clearance outline)
				(anchor circle)
			)
			(primitives
				(gr_poly
					(pts
						(arc
							(start 0.1524 -0.127)
							(mid 0.137521 -0.162921)
							(end 0.1016 -0.1778)
						)
						(arc
							(start -0.1016 -0.1778)
							(mid -0.137521 -0.162921)
							(end -0.1524 -0.127)
						)
						(arc
							(start -0.1524 0.127)
							(mid -0.137521 0.162921)
							(end -0.1016 0.1778)
						)
						(arc
							(start 0.1016 0.1778)
							(mid 0.137521 0.162921)
							(end 0.1524 0.127)
						)
					)
					(width 0)
					(fill yes)
				)
			)
		)
	)
	(footprint ""
		(layer "F.Cu")
		(at 176.2506 -275.633942)
		(property "Reference" "R262"
			(at 0 0 0)
			(layer "F.SilkS")
			(hide yes)
			(effects
				(font
					(size 1.27 1.27)
				)
			)
		)
		(property "Value" "0R2J-2-GP"
			(at 0.064008 -3.993896 0)
			(unlocked yes)
			(layer "F.Fab")
			(hide yes)
			(effects
				(font
					(size 1.016 1.016)
					(thickness 0.1524)
				)
			)
		)
		(property "Device Type" "R402H16"
			(at 0.064008 -5.517896 0)
			(unlocked yes)
			(layer "F.Fab")
			(hide yes)
			(effects
				(font
					(size 1.016 1.016)
					(thickness 0.1524)
				)
			)
		)
		(duplicate_pad_numbers_are_jumpers no)
		(fp_line
			(start -0.508 -0.9398)
			(end -0.508 0.9398)
			(stroke
				(width 0.1524)
				(type default)
			)
			(layer "F.SilkS")
		)
		(fp_line
			(start 0.508 -0.9398)
			(end -0.508 -0.9398)
			(stroke
				(width 0.1524)
				(type default)
			)
			(layer "F.SilkS")
		)
		(fp_rect
			(start -0.508 0.9398)
			(end 0.508 -0.9398)
			(stroke
				(width 0)
				(type default)
			)
			(fill no)
			(layer "F.CrtYd")
		)
		(fp_rect
			(start -0.508 0.9398)
			(end 0.508 -0.9398)
			(stroke
				(width 0)
				(type default)
			)
			(fill no)
			(layer "F.Fab")
		)
		(pad "1" smd custom
			(at 0 -0.4445)
			(size 0.1397 0.1397)
			(layers "F.Cu" "F.Mask" "F.Paste")
			(net "SW_HDD_G5")
			(options
				(clearance outline)
				(anchor circle)
			)
			(primitives
				(gr_poly
					(pts
						(arc
							(start -0.1778 -0.2794)
							(mid -0.249642 -0.249642)
							(end -0.2794 -0.1778)
						)
						(arc
							(start -0.2794 0.1778)
							(mid -0.249642 0.249642)
							(end -0.1778 0.2794)
						)
						(arc
							(start 0.1778 0.2794)
							(mid 0.249642 0.249642)
							(end 0.2794 0.1778)
						)
						(arc
							(start 0.2794 -0.1778)
							(mid 0.249642 -0.249642)
							(end 0.1778 -0.2794)
						)
					)
					(width 0)
					(fill yes)
				)
			)
		)
		(pad "2" smd custom
			(at 0 0.4445)
			(size 0.1397 0.1397)
			(layers "F.Cu" "F.Mask" "F.Paste")
			(net "SW_HDD_R5")
			(options
				(clearance outline)
				(anchor circle)
			)
			(primitives
				(gr_poly
					(pts
						(arc
							(start -0.1778 -0.2794)
							(mid -0.249642 -0.249642)
							(end -0.2794 -0.1778)
						)
						(arc
							(start -0.2794 0.1778)
							(mid -0.249642 0.249642)
							(end -0.1778 0.2794)
						)
						(arc
							(start 0.1778 0.2794)
							(mid 0.249642 0.249642)
							(end 0.2794 0.1778)
						)
						(arc
							(start 0.2794 -0.1778)
							(mid 0.249642 -0.249642)
							(end 0.1778 -0.2794)
						)
					)
					(width 0)
					(fill yes)
				)
			)
		)
	)
	(footprint ""
		(layer "F.Cu")
		(at 190.5 -172.1358 -90)
		(property "Reference" "R521"
			(at 0 0 270)
			(layer "F.SilkS")
			(hide yes)
			(effects
				(font
					(size 1.27 1.27)
				)
			)
		)
		(property "Value" "10KR2F-2-GP"
			(at 0.064008 -3.993896 270)
			(unlocked yes)
			(layer "F.Fab")
			(hide yes)
			(effects
				(font
					(size 1.016 1.016)
					(thickness 0.1524)
				)
			)
		)
		(property "Device Type" "R402H16"
			(at 0.064008 -5.517896 270)
			(unlocked yes)
			(layer "F.Fab")
			(hide yes)
			(effects
				(font
					(size 1.016 1.016)
					(thickness 0.1524)
				)
			)
		)
		(duplicate_pad_numbers_are_jumpers no)
		(fp_line
			(start -0.508 -0.9398)
			(end -0.508 0.9398)
			(stroke
				(width 0.1524)
				(type default)
			)
			(layer "F.SilkS")
		)
		(fp_line
			(start 0.508 -0.9398)
			(end -0.508 -0.9398)
			(stroke
				(width 0.1524)
				(type default)
			)
			(layer "F.SilkS")
		)
		(fp_rect
			(start -0.508 0.9398)
			(end 0.508 -0.9398)
			(stroke
				(width 0)
				(type default)
			)
			(fill no)
			(layer "F.CrtYd")
		)
		(fp_rect
			(start -0.508 0.9398)
			(end 0.508 -0.9398)
			(stroke
				(width 0)
				(type default)
			)
			(fill no)
			(layer "F.Fab")
		)
		(pad "1" smd custom
			(at 0 -0.4445 270)
			(size 0.1397 0.1397)
			(layers "F.Cu" "F.Mask" "F.Paste")
			(net "P3V3_STBY_A")
			(options
				(clearance outline)
				(anchor circle)
			)
			(primitives
				(gr_poly
					(pts
						(arc
							(start -0.1778 -0.2794)
							(mid -0.249642 -0.249642)
							(end -0.2794 -0.1778)
						)
						(arc
							(start -0.2794 0.1778)
							(mid -0.249642 0.249642)
							(end -0.1778 0.2794)
						)
						(arc
							(start 0.1778 0.2794)
							(mid 0.249642 0.249642)
							(end 0.2794 0.1778)
						)
						(arc
							(start 0.2794 -0.1778)
							(mid 0.249642 -0.249642)
							(end 0.1778 -0.2794)
						)
					)
					(width 0)
					(fill yes)
				)
			)
		)
		(pad "2" smd custom
			(at 0 0.4445 270)
			(size 0.1397 0.1397)
			(layers "F.Cu" "F.Mask" "F.Paste")
			(net "HDD_PRSNT_17")
			(options
				(clearance outline)
				(anchor circle)
			)
			(primitives
				(gr_poly
					(pts
						(arc
							(start -0.1778 -0.2794)
							(mid -0.249642 -0.249642)
							(end -0.2794 -0.1778)
						)
						(arc
							(start -0.2794 0.1778)
							(mid -0.249642 0.249642)
							(end -0.1778 0.2794)
						)
						(arc
							(start 0.1778 0.2794)
							(mid 0.249642 0.249642)
							(end 0.2794 0.1778)
						)
						(arc
							(start 0.2794 -0.1778)
							(mid 0.249642 -0.249642)
							(end 0.1778 -0.2794)
						)
					)
					(width 0)
					(fill yes)
				)
			)
		)
	)
)
